# BASEBOARD_FAB2 (Tioga Pass) — schematic netlist excerpt (pin names and nets, part order shuffled) for the footprints in the layout excerpt that follows; sources: Cadence DE-HDL packaged netlist, KiCad conversion of Wiwynn_Tioga_Pass_MB.brd

R2P4  RES  33.2 1% CHIP  pkg 0402  page 170 : A = IRQ_FORCE_NM_THROTTLE_R_N ; B = IRQ_FORCE_NM_THROTTLE_N
R8C15  RES  2.0K 1% CHIP  pkg 0402  page 159 : A = P3V3_STBY ; B = SMB_HOST_STBY_LVC3_SCL_R
R3D2  RES  90.9 1% CHIP  pkg 0402  page 55 : A = A_CPU1_KLM_RCOMP1 ; B = GND

(kicad_pcb
	(version 20260206)
	(generator "pcbnew")
	(generator_version "10.0")
	(general
		(thickness 1.6)
		(legacy_teardrops no)
	)
	(paper "A4")
	(title_block
		(title "Wiwynn_Tioga_Pass_MB.brd")
		(comment 1 "Tioga Pass / footprints 2310-2312 of 4770")
	)
	(layers
		(0 "F.Cu" signal "TOP")
		(4 "In1.Cu" signal "L2GND")
		(6 "In2.Cu" signal "L3")
		(8 "In3.Cu" signal "L4GND")
		(10 "In4.Cu" signal "L5")
		(12 "In5.Cu" signal "L6GND")
		(14 "In6.Cu" signal "L7VCC")
		(16 "In7.Cu" signal "L8VCC")
		(18 "In8.Cu" signal "L9GND")
		(20 "In9.Cu" signal "L10")
		(22 "In10.Cu" signal "L11GND")
		(24 "In11.Cu" signal "L12")
		(26 "In12.Cu" signal "L13GND")
		(2 "B.Cu" signal "BOTTOM")
		(9 "F.Adhes" user "F.Adhesive")
		(11 "B.Adhes" user "B.Adhesive")
		(13 "F.Paste" user "Package Geometry/Pastemask Top")
		(15 "B.Paste" user "Package Geometry/Pastemask Bottom")
		(5 "F.SilkS" user "Ref Des/Silkscreen Top")
		(7 "B.SilkS" user "Ref Des/Silkscreen Bottom")
		(1 "F.Mask" user "Board Geometry/Soldermask Top")
		(3 "B.Mask" user "Board Geometry/Soldermask Bottom")
		(17 "Dwgs.User" user "User.Drawings")
		(19 "Cmts.User" user "User.Comments")
		(21 "Eco1.User" user "User.Eco1")
		(23 "Eco2.User" user "User.Eco2")
		(25 "Edge.Cuts" user "Board Geometry/Outline")
		(27 "Margin" user)
		(31 "F.CrtYd" user "Package Geometry/Place Bound Top")
		(29 "B.CrtYd" user "Package Geometry/Place Bound Bottom")
		(35 "F.Fab" user "Ref Des/Assembly Top")
		(33 "B.Fab" user "Ref Des/Assembly Bottom")
	)
	(footprint ""
		(layer "F.Cu")
		(at 417.9951 -88.5825)
		(property "Reference" "R2P4"
			(at 0 0 0)
			(layer "F.SilkS")
			(hide yes)
			(effects
				(font
					(size 1.27 1.27)
				)
			)
		)
		(property "Value" ""
			(at 0 0 0)
			(layer "F.Fab")
			(effects
				(font
					(size 1.27 1.27)
				)
			)
		)
		(duplicate_pad_numbers_are_jumpers no)
		(fp_poly
			(pts
				(xy -0.2794 -0.1016) (xy 0.2794 -0.1016) (xy 0.2794 0.9906) (xy -0.2794 0.9906)
			)
			(stroke
				(width 0)
				(type default)
			)
			(fill no)
			(layer "F.CrtYd")
		)
		(fp_line
			(start -0.2794 -0.1016)
			(end -0.2794 0.9906)
			(stroke
				(width 0.1)
				(type default)
			)
			(layer "F.Fab")
		)
		(fp_line
			(start -0.2794 0.9906)
			(end 0.2794 0.9906)
			(stroke
				(width 0.1)
				(type default)
			)
			(layer "F.Fab")
		)
		(fp_line
			(start 0.2794 -0.1016)
			(end -0.2794 -0.1016)
			(stroke
				(width 0.1)
				(type default)
			)
			(layer "F.Fab")
		)
		(fp_line
			(start 0.2794 0.9906)
			(end 0.2794 -0.1016)
			(stroke
				(width 0.1)
				(type default)
			)
			(layer "F.Fab")
		)
		(pad "1" smd rect
			(at 0 0)
			(size 0.508 0.508)
			(layers "F.Cu" "F.Mask" "F.Paste")
			(net "IRQ_FORCE_NM_THROTTLE_R_N")
		)
		(pad "2" smd rect
			(at 0 0.889)
			(size 0.508 0.508)
			(layers "F.Cu" "F.Mask" "F.Paste")
			(net "IRQ_FORCE_NM_THROTTLE_N")
		)
		(zone
			(layer "F.Cu")
			(hatch none 0.5)
			(connect_pads
				(clearance 0)
			)
			(min_thickness 0.25)
			(keepout
				(tracks allowed)
				(vias not_allowed)
				(pads allowed)
				(copperpour not_allowed)
				(footprints allowed)
			)
			(placement
				(enabled no)
				(sheetname "")
			)
			(fill
				(thermal_gap 0.5)
				(thermal_bridge_width 0.5)
				(island_removal_mode 0)
			)
			(polygon
				(pts
					(xy 417.7411 -88.3285) (xy 418.2491 -88.3285) (xy 418.2491 -87.9475) (xy 417.7411 -87.9475)
				)
			)
		)
		(zone
			(layer "F.Cu")
			(hatch none 0.5)
			(connect_pads
				(clearance 0)
			)
			(min_thickness 0.25)
			(keepout
				(tracks not_allowed)
				(vias allowed)
				(pads allowed)
				(copperpour not_allowed)
				(footprints allowed)
			)
			(placement
				(enabled no)
				(sheetname "")
			)
			(fill
				(thermal_gap 0.5)
				(thermal_bridge_width 0.5)
				(island_removal_mode 0)
			)
			(polygon
				(pts
					(xy 417.7411 -87.9475) (xy 418.2491 -87.9475) (xy 418.2491 -88.3285) (xy 417.7411 -88.3285)
				)
			)
		)
	)
	(footprint ""
		(layer "F.Cu")
		(at 110.7694 -83.8962)
		(property "Reference" "R3D2"
			(at 0 0 0)
			(layer "F.SilkS")
			(hide yes)
			(effects
				(font
					(size 1.27 1.27)
				)
			)
		)
		(property "Value" ""
			(at 0 0 0)
			(layer "F.Fab")
			(effects
				(font
					(size 1.27 1.27)
				)
			)
		)
		(duplicate_pad_numbers_are_jumpers no)
		(fp_poly
			(pts
				(xy -0.2794 -0.1016) (xy 0.2794 -0.1016) (xy 0.2794 0.9906) (xy -0.2794 0.9906)
			)
			(stroke
				(width 0)
				(type default)
			)
			(fill no)
			(layer "F.CrtYd")
		)
		(fp_line
			(start -0.2794 -0.1016)
			(end -0.2794 0.9906)
			(stroke
				(width 0.1)
				(type default)
			)
			(layer "F.Fab")
		)
		(fp_line
			(start -0.2794 0.9906)
			(end 0.2794 0.9906)
			(stroke
				(width 0.1)
				(type default)
			)
			(layer "F.Fab")
		)
		(fp_line
			(start 0.2794 -0.1016)
			(end -0.2794 -0.1016)
			(stroke
				(width 0.1)
				(type default)
			)
			(layer "F.Fab")
		)
		(fp_line
			(start 0.2794 0.9906)
			(end 0.2794 -0.1016)
			(stroke
				(width 0.1)
				(type default)
			)
			(layer "F.Fab")
		)
		(pad "1" smd rect
			(at 0 0)
			(size 0.508 0.508)
			(layers "F.Cu" "F.Mask" "F.Paste")
			(net "A_CPU1_KLM_RCOMP1")
		)
		(pad "2" smd rect
			(at 0 0.889)
			(size 0.508 0.508)
			(layers "F.Cu" "F.Mask" "F.Paste")
			(net "GND")
		)
		(zone
			(layer "F.Cu")
			(hatch none 0.5)
			(connect_pads
				(clearance 0)
			)
			(min_thickness 0.25)
			(keepout
				(tracks allowed)
				(vias not_allowed)
				(pads allowed)
				(copperpour not_allowed)
				(footprints allowed)
			)
			(placement
				(enabled no)
				(sheetname "")
			)
			(fill
				(thermal_gap 0.5)
				(thermal_bridge_width 0.5)
				(island_removal_mode 0)
			)
			(polygon
				(pts
					(xy 110.5154 -83.6422) (xy 111.0234 -83.6422) (xy 111.0234 -83.2612) (xy 110.5154 -83.2612)
				)
			)
		)
		(zone
			(layer "F.Cu")
			(hatch none 0.5)
			(connect_pads
				(clearance 0)
			)
			(min_thickness 0.25)
			(keepout
				(tracks not_allowed)
				(vias allowed)
				(pads allowed)
				(copperpour not_allowed)
				(footprints allowed)
			)
			(placement
				(enabled no)
				(sheetname "")
			)
			(fill
				(thermal_gap 0.5)
				(thermal_bridge_width 0.5)
				(island_removal_mode 0)
			)
			(polygon
				(pts
					(xy 110.5154 -83.2612) (xy 111.0234 -83.2612) (xy 111.0234 -83.6422) (xy 110.5154 -83.6422)
				)
			)
		)
	)
	(footprint ""
		(layer "F.Cu")
		(at 401.701 -34.426652 90)
		(property "Reference" "R8C15"
			(at 0 0 90)
			(layer "F.SilkS")
			(hide yes)
			(effects
				(font
					(size 1.27 1.27)
				)
			)
		)
		(property "Value" ""
			(at 0 0 90)
			(layer "F.Fab")
			(effects
				(font
					(size 1.27 1.27)
				)
			)
		)
		(duplicate_pad_numbers_are_jumpers no)
		(fp_poly
			(pts
				(xy -0.2794 -0.1016) (xy 0.2794 -0.1016) (xy 0.2794 0.9906) (xy -0.2794 0.9906)
			)
			(stroke
				(width 0)
				(type default)
			)
			(fill no)
			(layer "F.CrtYd")
		)
		(fp_line
			(start 0.2794 -0.1016)
			(end -0.2794 -0.1016)
			(stroke
				(width 0.1)
				(type default)
			)
			(layer "F.Fab")
		)
		(fp_line
			(start -0.2794 -0.1016)
			(end -0.2794 0.9906)
			(stroke
				(width 0.1)
				(type default)
			)
			(layer "F.Fab")
		)
		(fp_line
			(start 0.2794 0.9906)
			(end 0.2794 -0.1016)
			(stroke
				(width 0.1)
				(type default)
			)
			(layer "F.Fab")
		)
		(fp_line
			(start -0.2794 0.9906)
			(end 0.2794 0.9906)
			(stroke
				(width 0.1)
				(type default)
			)
			(layer "F.Fab")
		)
		(pad "1" smd rect
			(at 0 0 90)
			(size 0.508 0.508)
			(layers "F.Cu" "F.Mask" "F.Paste")
			(net "P3V3_STBY")
		)
		(pad "2" smd rect
			(at 0 0.889 90)
			(size 0.508 0.508)
			(layers "F.Cu" "F.Mask" "F.Paste")
			(net "SMB_HOST_STBY_LVC3_SCL_R")
		)
		(zone
			(layer "F.Cu")
			(hatch none 0.5)
			(connect_pads
				(clearance 0)
			)
			(min_thickness 0.25)
			(keepout
				(tracks allowed)
				(vias not_allowed)
				(pads allowed)
				(copperpour not_allowed)
				(footprints allowed)
			)
			(placement
				(enabled no)
				(sheetname "")
			)
			(fill
				(thermal_gap 0.5)
				(thermal_bridge_width 0.5)
				(island_removal_mode 0)
			)
			(polygon
				(pts
					(xy 401.955 -34.172652) (xy 401.955 -34.680652) (xy 402.336 -34.680652) (xy 402.336 -34.172652)
				)
			)
		)
		(zone
			(layer "F.Cu")
			(hatch none 0.5)
			(connect_pads
				(clearance 0)
			)
			(min_thickness 0.25)
			(keepout
				(tracks not_allowed)
				(vias allowed)
				(pads allowed)
				(copperpour not_allowed)
				(footprints allowed)
			)
			(placement
				(enabled no)
				(sheetname "")
			)
			(fill
				(thermal_gap 0.5)
				(thermal_bridge_width 0.5)
				(island_removal_mode 0)
			)
			(polygon
				(pts
					(xy 402.336 -34.172652) (xy 402.336 -34.680652) (xy 401.955 -34.680652) (xy 401.955 -34.172652)
				)
			)
		)
	)
)
